# T6G (Grand Teton) — schematic netlist excerpt (pin names and nets, part order shuffled) for the footprints in the layout excerpt that follows; sources: Cadence DE-HDL packaged netlist, KiCad conversion of 04192023_DAF0TMB3IC0_F0TG_MB_C_brd_V02_OCP.brd

PC424_5  Q_CAP  1UF 25V 10% X6S  pkg C0402  page 220 : A = SW_P12V_AUX_PVDDCR_CPU1_P1_FLT ; B = GND
C1796  Q_CAP  0.1UF 25V 10% X7R  pkg 0402  page 248 : A = P3V3_AUX ; B = GND

PQ15  MOSFET_N  BSS138K IC  pkg SMLF  page 210
  DRAIN  = PVDDCR_SOC_P1_EN_GD
  GATE  = PVDDCR_SOC_P1_EN_RC
  SOURCE  = GND

(kicad_pcb
	(version 20260206)
	(generator "pcbnew")
	(generator_version "10.0")
	(general
		(thickness 1.6)
		(legacy_teardrops no)
	)
	(paper "A4")
	(title_block
		(title "04192023_DAF0TMB3IC0_F0TG_MB_C_brd_V02_OCP.brd")
		(comment 1 "Grand Teton / footprints 3083-3085 of 8354")
	)
	(layers
		(0 "F.Cu" signal "TOP")
		(4 "In1.Cu" signal "GND")
		(6 "In2.Cu" signal "IN1")
		(8 "In3.Cu" signal "GND1")
		(10 "In4.Cu" signal "IN2")
		(12 "In5.Cu" signal "GND2")
		(14 "In6.Cu" signal "IN3")
		(16 "In7.Cu" signal "GND3")
		(18 "In8.Cu" signal "VCC")
		(20 "In9.Cu" signal "VCC1")
		(22 "In10.Cu" signal "GND4")
		(24 "In11.Cu" signal "IN4")
		(26 "In12.Cu" signal "GND5")
		(28 "In13.Cu" signal "IN5")
		(30 "In14.Cu" signal "GND6")
		(32 "In15.Cu" signal "IN6")
		(34 "In16.Cu" signal "GND7")
		(2 "B.Cu" signal "BOTTOM")
		(9 "F.Adhes" user "F.Adhesive")
		(11 "B.Adhes" user "B.Adhesive")
		(13 "F.Paste" user "Package Geometry/Pastemask Top")
		(15 "B.Paste" user "Package Geometry/Pastemask Bottom")
		(5 "F.SilkS" user "Ref Des/Silkscreen Top")
		(7 "B.SilkS" user "Ref Des/Silkscreen Bottom")
		(1 "F.Mask" user "Board Geometry/Soldermask Top")
		(3 "B.Mask" user "Board Geometry/Soldermask Bottom")
		(17 "Dwgs.User" user "User.Drawings")
		(19 "Cmts.User" user "User.Comments")
		(21 "Eco1.User" user "User.Eco1")
		(23 "Eco2.User" user "User.Eco2")
		(25 "Edge.Cuts" user "Board Geometry/Outline")
		(27 "Margin" user)
		(31 "F.CrtYd" user "Package Geometry/Place Bound Top")
		(29 "B.CrtYd" user "Package Geometry/Place Bound Bottom")
		(35 "F.Fab" user "Ref Des/Assembly Top")
		(33 "B.Fab" user "Ref Des/Assembly Bottom")
	)
	(footprint ""
		(layer "F.Cu")
		(at 23.816818 -435.925214 180)
		(property "Reference" "C1796"
			(at 0 0 180)
			(layer "F.SilkS")
			(hide yes)
			(effects
				(font
					(size 1.27 1.27)
				)
			)
		)
		(property "Value" ""
			(at 0 0 180)
			(layer "F.Fab")
			(effects
				(font
					(size 1.27 1.27)
				)
			)
		)
		(duplicate_pad_numbers_are_jumpers no)
		(fp_line
			(start 0.7874 0.4064)
			(end -0.7874 0.4064)
			(stroke
				(width 0.1524)
				(type default)
			)
			(layer "F.SilkS")
		)
		(fp_line
			(start 0.7874 -0.4064)
			(end 0.7874 0.4064)
			(stroke
				(width 0.1524)
				(type default)
			)
			(layer "F.SilkS")
		)
		(fp_line
			(start -0.7874 0.4064)
			(end -0.7874 -0.4064)
			(stroke
				(width 0.1524)
				(type default)
			)
			(layer "F.SilkS")
		)
		(fp_line
			(start -0.7874 -0.4064)
			(end 0.7874 -0.4064)
			(stroke
				(width 0.1524)
				(type default)
			)
			(layer "F.SilkS")
		)
		(fp_line
			(start 0.67945 0.3048)
			(end 0.120396 0.3048)
			(stroke
				(width 0.1)
				(type default)
			)
			(layer "F.Fab")
		)
		(fp_line
			(start 0.67945 -0.3048)
			(end 0.67945 0.3048)
			(stroke
				(width 0.1)
				(type default)
			)
			(layer "F.Fab")
		)
		(fp_line
			(start 0.12065 -0.2794)
			(end 0.12065 -0.3048)
			(stroke
				(width 0.1)
				(type default)
			)
			(layer "F.Fab")
		)
		(fp_line
			(start 0.12065 -0.3048)
			(end 0.67945 -0.3048)
			(stroke
				(width 0.1)
				(type default)
			)
			(layer "F.Fab")
		)
		(fp_line
			(start 0.120396 0.3048)
			(end 0.120396 0.2794)
			(stroke
				(width 0.1)
				(type default)
			)
			(layer "F.Fab")
		)
		(fp_line
			(start 0.120396 0.2794)
			(end -0.12065 0.2794)
			(stroke
				(width 0.1)
				(type default)
			)
			(layer "F.Fab")
		)
		(fp_line
			(start -0.12065 0.3048)
			(end -0.67945 0.3048)
			(stroke
				(width 0.1)
				(type default)
			)
			(layer "F.Fab")
		)
		(fp_line
			(start -0.12065 0.2794)
			(end -0.12065 0.3048)
			(stroke
				(width 0.1)
				(type default)
			)
			(layer "F.Fab")
		)
		(fp_line
			(start -0.12065 -0.2794)
			(end 0.12065 -0.2794)
			(stroke
				(width 0.1)
				(type default)
			)
			(layer "F.Fab")
		)
		(fp_line
			(start -0.12065 -0.305054)
			(end -0.12065 -0.2794)
			(stroke
				(width 0.1)
				(type default)
			)
			(layer "F.Fab")
		)
		(fp_line
			(start -0.67945 0.3048)
			(end -0.67945 -0.305054)
			(stroke
				(width 0.1)
				(type default)
			)
			(layer "F.Fab")
		)
		(fp_line
			(start -0.67945 -0.305054)
			(end -0.12065 -0.305054)
			(stroke
				(width 0.1)
				(type default)
			)
			(layer "F.Fab")
		)
		(pad "1" smd circle
			(at -0.40005 0 180)
			(size 0 0)
			(layers "F.Cu" "F.Mask" "F.Paste")
			(net "P3V3_AUX")
		)
		(pad "2" smd circle
			(at 0.40005 0 180)
			(size 0 0)
			(layers "F.Cu" "F.Mask" "F.Paste")
			(net "GND")
		)
	)
	(footprint ""
		(layer "F.Cu")
		(at 99.08794 -335.179416 -90)
		(property "Reference" "PC424_5"
			(at 0 0 270)
			(layer "F.SilkS")
			(hide yes)
			(effects
				(font
					(size 1.27 1.27)
				)
			)
		)
		(property "Value" ""
			(at 0 0 270)
			(layer "F.Fab")
			(effects
				(font
					(size 1.27 1.27)
				)
			)
		)
		(duplicate_pad_numbers_are_jumpers no)
		(fp_line
			(start -0.7874 0.4064)
			(end -0.7874 -0.4064)
			(stroke
				(width 0.1524)
				(type default)
			)
			(layer "F.SilkS")
		)
		(fp_line
			(start 0.7874 0.4064)
			(end -0.7874 0.4064)
			(stroke
				(width 0.1524)
				(type default)
			)
			(layer "F.SilkS")
		)
		(fp_line
			(start -0.7874 -0.4064)
			(end 0.7874 -0.4064)
			(stroke
				(width 0.1524)
				(type default)
			)
			(layer "F.SilkS")
		)
		(fp_line
			(start 0.7874 -0.4064)
			(end 0.7874 0.4064)
			(stroke
				(width 0.1524)
				(type default)
			)
			(layer "F.SilkS")
		)
		(fp_line
			(start -0.67945 0.3048)
			(end -0.67945 -0.305054)
			(stroke
				(width 0.1)
				(type default)
			)
			(layer "F.Fab")
		)
		(fp_line
			(start -0.12065 0.3048)
			(end -0.67945 0.3048)
			(stroke
				(width 0.1)
				(type default)
			)
			(layer "F.Fab")
		)
		(fp_line
			(start 0.120396 0.3048)
			(end 0.120396 0.2794)
			(stroke
				(width 0.1)
				(type default)
			)
			(layer "F.Fab")
		)
		(fp_line
			(start 0.67945 0.3048)
			(end 0.120396 0.3048)
			(stroke
				(width 0.1)
				(type default)
			)
			(layer "F.Fab")
		)
		(fp_line
			(start -0.12065 0.2794)
			(end -0.12065 0.3048)
			(stroke
				(width 0.1)
				(type default)
			)
			(layer "F.Fab")
		)
		(fp_line
			(start 0.120396 0.2794)
			(end -0.12065 0.2794)
			(stroke
				(width 0.1)
				(type default)
			)
			(layer "F.Fab")
		)
		(fp_line
			(start -0.12065 -0.2794)
			(end 0.12065 -0.2794)
			(stroke
				(width 0.1)
				(type default)
			)
			(layer "F.Fab")
		)
		(fp_line
			(start 0.12065 -0.2794)
			(end 0.12065 -0.3048)
			(stroke
				(width 0.1)
				(type default)
			)
			(layer "F.Fab")
		)
		(fp_line
			(start 0.12065 -0.3048)
			(end 0.67945 -0.3048)
			(stroke
				(width 0.1)
				(type default)
			)
			(layer "F.Fab")
		)
		(fp_line
			(start 0.67945 -0.3048)
			(end 0.67945 0.3048)
			(stroke
				(width 0.1)
				(type default)
			)
			(layer "F.Fab")
		)
		(fp_line
			(start -0.67945 -0.305054)
			(end -0.12065 -0.305054)
			(stroke
				(width 0.1)
				(type default)
			)
			(layer "F.Fab")
		)
		(fp_line
			(start -0.12065 -0.305054)
			(end -0.12065 -0.2794)
			(stroke
				(width 0.1)
				(type default)
			)
			(layer "F.Fab")
		)
		(pad "1" smd circle
			(at -0.40005 0 270)
			(size 0 0)
			(layers "F.Cu" "F.Mask" "F.Paste")
			(net "SW_P12V_AUX_PVDDCR_CPU1_P1_FLT")
		)
		(pad "2" smd circle
			(at 0.40005 0 270)
			(size 0 0)
			(layers "F.Cu" "F.Mask" "F.Paste")
			(net "GND")
		)
	)
	(footprint ""
		(layer "F.Cu")
		(at 99.509834 -136.179052)
		(property "Reference" "PQ15"
			(at 1.15316 2.498852 0)
			(unlocked yes)
			(layer "F.SilkS")
			(effects
				(font
					(size 0.7874 0.5842)
					(thickness 0.1524)
				)
			)
		)
		(property "Value" ""
			(at 0 0 0)
			(layer "F.Fab")
			(effects
				(font
					(size 1.27 1.27)
				)
			)
		)
		(duplicate_pad_numbers_are_jumpers no)
		(fp_line
			(start -1.949958 -1.610106)
			(end 1.949958 -1.610106)
			(stroke
				(width 0.1524)
				(type default)
			)
			(layer "F.SilkS")
		)
		(fp_line
			(start -1.949958 1.610106)
			(end -1.949958 -1.610106)
			(stroke
				(width 0.1524)
				(type default)
			)
			(layer "F.SilkS")
		)
		(fp_line
			(start 1.949958 -1.560068)
			(end 1.949958 1.610106)
			(stroke
				(width 0.1524)
				(type default)
			)
			(layer "F.SilkS")
		)
		(fp_line
			(start 1.949958 1.610106)
			(end -1.949958 1.610106)
			(stroke
				(width 0.1524)
				(type default)
			)
			(layer "F.SilkS")
		)
		(fp_line
			(start -0.750062 -1.560068)
			(end 0.750062 -1.560068)
			(stroke
				(width 0.1)
				(type default)
			)
			(layer "F.Fab")
		)
		(fp_line
			(start -0.750062 1.560068)
			(end -0.750062 -1.560068)
			(stroke
				(width 0.1)
				(type default)
			)
			(layer "F.Fab")
		)
		(fp_line
			(start 0.750062 -1.560068)
			(end 0.750062 1.560068)
			(stroke
				(width 0.1)
				(type default)
			)
			(layer "F.Fab")
		)
		(fp_line
			(start 0.750062 1.560068)
			(end -0.750062 1.560068)
			(stroke
				(width 0.1)
				(type default)
			)
			(layer "F.Fab")
		)
		(pad "D" smd rect
			(at 1.100074 0 270)
			(size 1.016 1.4224)
			(layers "F.Cu" "F.Mask" "F.Paste")
			(net "PVDDCR_SOC_P1_EN_GD")
		)
		(pad "G" smd rect
			(at -1.100074 -0.94996 270)
			(size 1.016 1.4224)
			(layers "F.Cu" "F.Mask" "F.Paste")
			(net "PVDDCR_SOC_P1_EN_RC")
		)
		(pad "S" smd rect
			(at -1.100074 0.94996 270)
			(size 1.016 1.4224)
			(layers "F.Cu" "F.Mask" "F.Paste")
			(net "GND")
		)
	)
)
